(kicad_pcb
	(version 20260206)
	(generator "pcbnew")
	(generator_version "10.0")
	(general
		(thickness 1.6)
		(legacy_teardrops no)
	)
	(paper "A4")
	(title_block
		(title "dpb — 14545-sa.0730WZS0815.brd")
		(comment 1 "Honey Badger (Wiwynn) / footprints 41-47 of 1066")
	)
	(layers
		(0 "F.Cu" signal "TOP")
		(4 "In1.Cu" signal "L2GND")
		(6 "In2.Cu" signal "L3")
		(8 "In3.Cu" signal "L4VCC")
		(10 "In4.Cu" signal "L5VCC")
		(12 "In5.Cu" signal "L6")
		(14 "In6.Cu" signal "L7GND")
		(2 "B.Cu" signal "BOTTOM")
		(9 "F.Adhes" user "F.Adhesive")
		(11 "B.Adhes" user "B.Adhesive")
		(13 "F.Paste" user "Package Geometry/Pastemask Top")
		(15 "B.Paste" user "Package Geometry/Pastemask Bottom")
		(5 "F.SilkS" user "Ref Des/Silkscreen Top")
		(7 "B.SilkS" user "Ref Des/Silkscreen Bottom")
		(1 "F.Mask" user "Board Geometry/Soldermask Top")
		(3 "B.Mask" user "Board Geometry/Soldermask Bottom")
		(17 "Dwgs.User" user "User.Drawings")
		(19 "Cmts.User" user "User.Comments")
		(21 "Eco1.User" user "User.Eco1")
		(23 "Eco2.User" user "User.Eco2")
		(25 "Edge.Cuts" user "Board Geometry/Outline")
		(27 "Margin" user)
		(31 "F.CrtYd" user "Package Geometry/Place Bound Top")
		(29 "B.CrtYd" user "Package Geometry/Place Bound Bottom")
		(35 "F.Fab" user "Ref Des/Assembly Top")
		(33 "B.Fab" user "Ref Des/Assembly Bottom")
	)
	(footprint ""
		(layer "F.Cu")
		(at 210.2358 -376.5296)
		(property "Reference" "R344"
			(at 0 0 0)
			(layer "F.SilkS")
			(hide yes)
			(effects
				(font
					(size 1.27 1.27)
				)
			)
		)
		(property "Value" "10KR2F-2-GP"
			(at 0.064008 -3.993896 0)
			(unlocked yes)
			(layer "F.Fab")
			(hide yes)
			(effects
				(font
					(size 1.016 1.016)
					(thickness 0.1524)
				)
			)
		)
		(property "Device Type" "R402H16"
			(at 0.064008 -5.517896 0)
			(unlocked yes)
			(layer "F.Fab")
			(hide yes)
			(effects
				(font
					(size 1.016 1.016)
					(thickness 0.1524)
				)
			)
		)
		(duplicate_pad_numbers_are_jumpers no)
		(fp_line
			(start -0.508 -0.9398)
			(end -0.508 0.9398)
			(stroke
				(width 0.1524)
				(type default)
			)
			(layer "F.SilkS")
		)
		(fp_line
			(start 0.508 -0.9398)
			(end -0.508 -0.9398)
			(stroke
				(width 0.1524)
				(type default)
			)
			(layer "F.SilkS")
		)
		(fp_rect
			(start -0.508 0.9398)
			(end 0.508 -0.9398)
			(stroke
				(width 0)
				(type default)
			)
			(fill no)
			(layer "F.CrtYd")
		)
		(fp_rect
			(start -0.508 0.9398)
			(end 0.508 -0.9398)
			(stroke
				(width 0)
				(type default)
			)
			(fill no)
			(layer "F.Fab")
		)
		(pad "1" smd custom
			(at 0 -0.4445)
			(size 0.1397 0.1397)
			(layers "F.Cu" "F.Mask" "F.Paste")
			(net "P12V")
			(options
				(clearance outline)
				(anchor circle)
			)
			(primitives
				(gr_poly
					(pts
						(arc
							(start -0.1778 -0.2794)
							(mid -0.249642 -0.249642)
							(end -0.2794 -0.1778)
						)
						(arc
							(start -0.2794 0.1778)
							(mid -0.249642 0.249642)
							(end -0.1778 0.2794)
						)
						(arc
							(start 0.1778 0.2794)
							(mid 0.249642 0.249642)
							(end 0.2794 0.1778)
						)
						(arc
							(start 0.2794 -0.1778)
							(mid 0.249642 -0.249642)
							(end 0.1778 -0.2794)
						)
					)
					(width 0)
					(fill yes)
				)
			)
		)
		(pad "2" smd custom
			(at 0 0.4445)
			(size 0.1397 0.1397)
			(layers "F.Cu" "F.Mask" "F.Paste")
			(net "HDD1_LED_G")
			(options
				(clearance outline)
				(anchor circle)
			)
			(primitives
				(gr_poly
					(pts
						(arc
							(start -0.1778 -0.2794)
							(mid -0.249642 -0.249642)
							(end -0.2794 -0.1778)
						)
						(arc
							(start -0.2794 0.1778)
							(mid -0.249642 0.249642)
							(end -0.1778 0.2794)
						)
						(arc
							(start 0.1778 0.2794)
							(mid 0.249642 0.249642)
							(end 0.2794 0.1778)
						)
						(arc
							(start 0.2794 -0.1778)
							(mid 0.249642 -0.249642)
							(end 0.1778 -0.2794)
						)
					)
					(width 0)
					(fill yes)
				)
			)
		)
	)
	(footprint ""
		(layer "F.Cu")
		(at 232.384346 -244.3734 -90)
		(property "Reference" "R490"
			(at 0 0 270)
			(layer "F.SilkS")
			(hide yes)
			(effects
				(font
					(size 1.27 1.27)
				)
			)
		)
		(property "Value" "1KR2F-3-GP"
			(at 0.064008 -3.993896 270)
			(unlocked yes)
			(layer "F.Fab")
			(hide yes)
			(effects
				(font
					(size 1.016 1.016)
					(thickness 0.1524)
				)
			)
		)
		(property "Device Type" "R402H16"
			(at 0.064008 -5.517896 270)
			(unlocked yes)
			(layer "F.Fab")
			(hide yes)
			(effects
				(font
					(size 1.016 1.016)
					(thickness 0.1524)
				)
			)
		)
		(duplicate_pad_numbers_are_jumpers no)
		(fp_line
			(start -0.508 -0.9398)
			(end -0.508 0.9398)
			(stroke
				(width 0.1524)
				(type default)
			)
			(layer "F.SilkS")
		)
		(fp_line
			(start 0.508 -0.9398)
			(end -0.508 -0.9398)
			(stroke
				(width 0.1524)
				(type default)
			)
			(layer "F.SilkS")
		)
		(fp_rect
			(start -0.508 0.9398)
			(end 0.508 -0.9398)
			(stroke
				(width 0)
				(type default)
			)
			(fill no)
			(layer "F.CrtYd")
		)
		(fp_rect
			(start -0.508 0.9398)
			(end 0.508 -0.9398)
			(stroke
				(width 0)
				(type default)
			)
			(fill no)
			(layer "F.Fab")
		)
		(pad "1" smd custom
			(at 0 -0.4445 270)
			(size 0.1397 0.1397)
			(layers "F.Cu" "F.Mask" "F.Paste")
			(net "FLT_HDD2_B")
			(options
				(clearance outline)
				(anchor circle)
			)
			(primitives
				(gr_poly
					(pts
						(arc
							(start -0.1778 -0.2794)
							(mid -0.249642 -0.249642)
							(end -0.2794 -0.1778)
						)
						(arc
							(start -0.2794 0.1778)
							(mid -0.249642 0.249642)
							(end -0.1778 0.2794)
						)
						(arc
							(start 0.1778 0.2794)
							(mid 0.249642 0.249642)
							(end 0.2794 0.1778)
						)
						(arc
							(start 0.2794 -0.1778)
							(mid 0.249642 -0.249642)
							(end 0.1778 -0.2794)
						)
					)
					(width 0)
					(fill yes)
				)
			)
		)
		(pad "2" smd custom
			(at 0 0.4445 270)
			(size 0.1397 0.1397)
			(layers "F.Cu" "F.Mask" "F.Paste")
			(net "FLT_HDD2_DRIVE")
			(options
				(clearance outline)
				(anchor circle)
			)
			(primitives
				(gr_poly
					(pts
						(arc
							(start -0.1778 -0.2794)
							(mid -0.249642 -0.249642)
							(end -0.2794 -0.1778)
						)
						(arc
							(start -0.2794 0.1778)
							(mid -0.249642 0.249642)
							(end -0.1778 0.2794)
						)
						(arc
							(start 0.1778 0.2794)
							(mid 0.249642 0.249642)
							(end 0.2794 0.1778)
						)
						(arc
							(start 0.2794 -0.1778)
							(mid 0.249642 -0.249642)
							(end 0.1778 -0.2794)
						)
					)
					(width 0)
					(fill yes)
				)
			)
		)
	)
	(footprint ""
		(layer "F.Cu")
		(at 215.281256 -484.457502 -90)
		(property "Reference" "R100"
			(at 0 0 270)
			(layer "F.SilkS")
			(hide yes)
			(effects
				(font
					(size 1.27 1.27)
				)
			)
		)
		(property "Value" "2R2010J-1-GP"
			(at 0.254 -8.0772 270)
			(unlocked yes)
			(layer "F.Fab")
			(hide yes)
			(effects
				(font
					(size 1.016 1.016)
					(thickness 0.1524)
				)
			)
		)
		(property "Device Type" "R2010H28"
			(at 0.254 -9.6774 270)
			(unlocked yes)
			(layer "F.Fab")
			(hide yes)
			(effects
				(font
					(size 1.016 1.016)
					(thickness 0.1524)
				)
			)
		)
		(duplicate_pad_numbers_are_jumpers no)
		(fp_line
			(start -1.651 3.302)
			(end 1.651 3.302)
			(stroke
				(width 0.1524)
				(type default)
			)
			(layer "F.SilkS")
		)
		(fp_line
			(start 1.651 3.302)
			(end 1.651 -3.302)
			(stroke
				(width 0.1524)
				(type default)
			)
			(layer "F.SilkS")
		)
		(fp_line
			(start -1.651 -3.302)
			(end -1.651 3.302)
			(stroke
				(width 0.1524)
				(type default)
			)
			(layer "F.SilkS")
		)
		(fp_line
			(start 1.651 -3.302)
			(end -1.651 -3.302)
			(stroke
				(width 0.1524)
				(type default)
			)
			(layer "F.SilkS")
		)
		(fp_rect
			(start -1.7272 -3.3782)
			(end 1.7272 3.3782)
			(stroke
				(width 0)
				(type default)
			)
			(fill no)
			(layer "F.CrtYd")
		)
		(fp_poly
			(pts
				(xy 1.7272 3.3782) (xy 1.7272 -3.3782) (xy -1.7272 -3.3782) (xy -1.7272 3.3782)
			)
			(stroke
				(width 0)
				(type default)
			)
			(fill no)
			(layer "F.Fab")
		)
		(pad "1" smd rect
			(at 0 -2.3495 270)
			(size 2.794 1.143)
			(layers "F.Cu" "F.Mask" "F.Paste")
			(net "5V_PRE_0")
		)
		(pad "2" smd rect
			(at 0 2.3495 270)
			(size 2.794 1.143)
			(layers "F.Cu" "F.Mask" "F.Paste")
			(net "P5V_HDD0")
		)
	)
	(footprint ""
		(layer "F.Cu")
		(at 23.114 -394.589 90)
		(property "Reference" "R510"
			(at 0 0 90)
			(layer "F.SilkS")
			(hide yes)
			(effects
				(font
					(size 1.27 1.27)
				)
			)
		)
		(property "Value" "0R2J-2-GP"
			(at 0.064008 -3.993896 90)
			(unlocked yes)
			(layer "F.Fab")
			(hide yes)
			(effects
				(font
					(size 1.016 1.016)
					(thickness 0.1524)
				)
			)
		)
		(property "Device Type" "R402H16"
			(at 0.064008 -5.517896 90)
			(unlocked yes)
			(layer "F.Fab")
			(hide yes)
			(effects
				(font
					(size 1.016 1.016)
					(thickness 0.1524)
				)
			)
		)
		(duplicate_pad_numbers_are_jumpers no)
		(fp_line
			(start 0.508 -0.9398)
			(end -0.508 -0.9398)
			(stroke
				(width 0.1524)
				(type default)
			)
			(layer "F.SilkS")
		)
		(fp_line
			(start -0.508 -0.9398)
			(end -0.508 0.9398)
			(stroke
				(width 0.1524)
				(type default)
			)
			(layer "F.SilkS")
		)
		(fp_rect
			(start -0.508 0.9398)
			(end 0.508 -0.9398)
			(stroke
				(width 0)
				(type default)
			)
			(fill no)
			(layer "F.CrtYd")
		)
		(fp_rect
			(start -0.508 0.9398)
			(end 0.508 -0.9398)
			(stroke
				(width 0)
				(type default)
			)
			(fill no)
			(layer "F.Fab")
		)
		(pad "1" smd custom
			(at 0 -0.4445 90)
			(size 0.1397 0.1397)
			(layers "F.Cu" "F.Mask" "F.Paste")
			(net "I2C_B_SCL_DAMP_A")
			(options
				(clearance outline)
				(anchor circle)
			)
			(primitives
				(gr_poly
					(pts
						(arc
							(start -0.1778 -0.2794)
							(mid -0.249642 -0.249642)
							(end -0.2794 -0.1778)
						)
						(arc
							(start -0.2794 0.1778)
							(mid -0.249642 0.249642)
							(end -0.1778 0.2794)
						)
						(arc
							(start 0.1778 0.2794)
							(mid 0.249642 0.249642)
							(end 0.2794 0.1778)
						)
						(arc
							(start 0.2794 -0.1778)
							(mid 0.249642 -0.249642)
							(end 0.1778 -0.2794)
						)
					)
					(width 0)
					(fill yes)
				)
			)
		)
		(pad "2" smd custom
			(at 0 0.4445 90)
			(size 0.1397 0.1397)
			(layers "F.Cu" "F.Mask" "F.Paste")
			(net "I2C_B_SCL")
			(options
				(clearance outline)
				(anchor circle)
			)
			(primitives
				(gr_poly
					(pts
						(arc
							(start -0.1778 -0.2794)
							(mid -0.249642 -0.249642)
							(end -0.2794 -0.1778)
						)
						(arc
							(start -0.2794 0.1778)
							(mid -0.249642 0.249642)
							(end -0.1778 0.2794)
						)
						(arc
							(start 0.1778 0.2794)
							(mid 0.249642 0.249642)
							(end 0.2794 0.1778)
						)
						(arc
							(start 0.2794 -0.1778)
							(mid 0.249642 -0.249642)
							(end 0.1778 -0.2794)
						)
					)
					(width 0)
					(fill yes)
				)
			)
		)
	)
	(footprint ""
		(layer "F.Cu")
		(at 200.489058 -395.299184 -90)
		(property "Reference" "U5"
			(at 0 0 270)
			(layer "F.SilkS")
			(hide yes)
			(effects
				(font
					(size 1.27 1.27)
				)
			)
		)
		(property "Value" "P2003EVG-GP"
			(at 0 -11.1252 270)
			(unlocked yes)
			(layer "F.Fab")
			(hide yes)
			(effects
				(font
					(size 1.016 1.016)
					(thickness 0.1524)
				)
			)
		)
		(property "Device Type" "SOIC8H79"
			(at 0 -12.6492 270)
			(unlocked yes)
			(layer "F.Fab")
			(hide yes)
			(effects
				(font
					(size 1.016 1.016)
					(thickness 0.1524)
				)
			)
		)
		(duplicate_pad_numbers_are_jumpers no)
		(fp_line
			(start -2.6162 3.429)
			(end -2.6162 1.4732)
			(stroke
				(width 0.4064)
				(type default)
			)
			(layer "F.SilkS")
		)
		(fp_line
			(start -2.7432 1.4224)
			(end 2.1336 1.4224)
			(stroke
				(width 0.1524)
				(type default)
			)
			(layer "F.SilkS")
		)
		(fp_line
			(start 2.1336 1.4224)
			(end 2.1336 -1.4224)
			(stroke
				(width 0.1524)
				(type default)
			)
			(layer "F.SilkS")
		)
		(fp_line
			(start -2.2352 0)
			(end -2.7432 0.508)
			(stroke
				(width 0.1524)
				(type default)
			)
			(layer "F.SilkS")
		)
		(fp_line
			(start -2.7432 -0.508)
			(end -2.2352 0)
			(stroke
				(width 0.1524)
				(type default)
			)
			(layer "F.SilkS")
		)
		(fp_line
			(start -2.7432 -1.4224)
			(end -2.7432 1.4224)
			(stroke
				(width 0.1524)
				(type default)
			)
			(layer "F.SilkS")
		)
		(fp_line
			(start 2.1336 -1.4224)
			(end -2.7432 -1.4224)
			(stroke
				(width 0.1524)
				(type default)
			)
			(layer "F.SilkS")
		)
		(fp_poly
			(pts
				(xy 2.2098 -1.4224) (xy 2.2098 1.4224) (xy -2.2225 1.4224) (xy -2.2225 -1.4224)
			)
			(stroke
				(width 0)
				(type default)
			)
			(fill yes)
			(layer "F.SilkS")
		)
		(fp_rect
			(start -2.4511 2.9972)
			(end 2.4511 -2.9972)
			(stroke
				(width 0)
				(type default)
			)
			(fill no)
			(layer "F.CrtYd")
		)
		(fp_poly
			(pts
				(xy -2.8194 3.6322) (xy -2.8194 -3.6322) (xy 2.8194 -3.6322) (xy 2.8194 -2.2987) (xy 2.4511 -2.2987)
				(xy 2.4511 -2.9972) (xy -2.4511 -2.9972) (xy -2.4511 2.9972) (xy 2.4511 2.9972) (xy 2.4511 -2.286)
				(xy 2.8194 -2.286) (xy 2.8194 3.6322)
			)
			(stroke
				(width 0)
				(type default)
			)
			(fill no)
			(layer "F.CrtYd")
		)
		(fp_rect
			(start -2.8194 3.6322)
			(end 2.8194 -3.6322)
			(stroke
				(width 0)
				(type default)
			)
			(fill no)
			(layer "F.Fab")
		)
		(pad "1" smd rect
			(at -1.905 2.54 270)
			(size 0.635 1.651)
			(layers "F.Cu" "F.Mask" "F.Paste")
			(net "P12V")
		)
		(pad "2" smd rect
			(at -0.635 2.54 270)
			(size 0.635 1.651)
			(layers "F.Cu" "F.Mask" "F.Paste")
			(net "P12V")
		)
		(pad "3" smd rect
			(at 0.635 2.54 270)
			(size 0.635 1.651)
			(layers "F.Cu" "F.Mask" "F.Paste")
			(net "P12V")
		)
		(pad "4" smd rect
			(at 1.905 2.54 270)
			(size 0.635 1.651)
			(layers "F.Cu" "F.Mask" "F.Paste")
			(net "SW_HDD1_N")
		)
		(pad "5" smd rect
			(at 1.905 -2.54 270)
			(size 0.635 1.651)
			(layers "F.Cu" "F.Mask" "F.Paste")
			(net "P12V_HDD1")
		)
		(pad "6" smd rect
			(at 0.635 -2.54 270)
			(size 0.635 1.651)
			(layers "F.Cu" "F.Mask" "F.Paste")
			(net "P12V_HDD1")
		)
		(pad "7" smd rect
			(at -0.635 -2.54 270)
			(size 0.635 1.651)
			(layers "F.Cu" "F.Mask" "F.Paste")
			(net "P12V_HDD1")
		)
		(pad "8" smd rect
			(at -1.905 -2.54 270)
			(size 0.635 1.651)
			(layers "F.Cu" "F.Mask" "F.Paste")
			(net "P12V_HDD1")
		)
	)
	(footprint ""
		(layer "F.Cu")
		(at 41.147746 -233.073702 180)
		(property "Reference" "C303"
			(at 0 0 180)
			(layer "F.SilkS")
			(hide yes)
			(effects
				(font
					(size 1.27 1.27)
				)
			)
		)
		(property "Value" "SCD01U50V2KX-1GP"
			(at 1.1811 -2.7051 180)
			(unlocked yes)
			(layer "F.Fab")
			(hide yes)
			(effects
				(font
					(size 1.016 1.016)
					(thickness 0.1524)
				)
			)
		)
		(property "Device Type" "C402H22"
			(at 1.1811 -4.2291 180)
			(unlocked yes)
			(layer "F.Fab")
			(hide yes)
			(effects
				(font
					(size 1.016 1.016)
					(thickness 0.1524)
				)
			)
		)
		(duplicate_pad_numbers_are_jumpers no)
		(fp_rect
			(start -0.4318 0.9525)
			(end 0.4318 -0.9525)
			(stroke
				(width 0)
				(type default)
			)
			(fill no)
			(layer "F.CrtYd")
		)
		(fp_rect
			(start -0.4318 0.9525)
			(end 0.4318 -0.9525)
			(stroke
				(width 0)
				(type default)
			)
			(fill no)
			(layer "F.Fab")
		)
		(pad "1" smd custom
			(at 0 -0.4445 180)
			(size 0.1524 0.1524)
			(layers "F.Cu" "F.Mask" "F.Paste")
			(net "HDD_PRSNT_NET12")
			(options
				(clearance outline)
				(anchor circle)
			)
			(primitives
				(gr_poly
					(pts
						(arc
							(start 0.3048 -0.2032)
							(mid 0.275042 -0.275042)
							(end 0.2032 -0.3048)
						)
						(arc
							(start -0.2032 -0.3048)
							(mid -0.275042 -0.275042)
							(end -0.3048 -0.2032)
						)
						(arc
							(start -0.3048 0.2032)
							(mid -0.275042 0.275042)
							(end -0.2032 0.3048)
						)
						(arc
							(start 0.2032 0.3048)
							(mid 0.275042 0.275042)
							(end 0.3048 0.2032)
						)
					)
					(width 0)
					(fill yes)
				)
			)
		)
		(pad "2" smd custom
			(at 0 0.4445 180)
			(size 0.1524 0.1524)
			(layers "F.Cu" "F.Mask" "F.Paste")
			(net "GND")
			(options
				(clearance outline)
				(anchor circle)
			)
			(primitives
				(gr_poly
					(pts
						(arc
							(start 0.3048 -0.2032)
							(mid 0.275042 -0.275042)
							(end 0.2032 -0.3048)
						)
						(arc
							(start -0.2032 -0.3048)
							(mid -0.275042 -0.275042)
							(end -0.3048 -0.2032)
						)
						(arc
							(start -0.3048 0.2032)
							(mid -0.275042 0.275042)
							(end -0.2032 0.3048)
						)
						(arc
							(start 0.2032 0.3048)
							(mid 0.275042 0.275042)
							(end 0.3048 0.2032)
						)
					)
					(width 0)
					(fill yes)
				)
			)
		)
	)
	(footprint ""
		(layer "F.Cu")
		(at 55.578756 -488.470702 180)
		(property "Reference" "C188"
			(at 0 0 180)
			(layer "F.SilkS")
			(hide yes)
			(effects
				(font
					(size 1.27 1.27)
				)
			)
		)
		(property "Value" "SC1U16V3KX-5GP"
			(at 0 -2.8194 180)
			(unlocked yes)
			(layer "F.Fab")
			(hide yes)
			(effects
				(font
					(size 1.016 1.016)
					(thickness 0.1524)
				)
			)
		)
		(property "Device Type" "C603H36"
			(at 0 -4.3434 180)
			(unlocked yes)
			(layer "F.Fab")
			(hide yes)
			(effects
				(font
					(size 1.016 1.016)
					(thickness 0.1524)
				)
			)
		)
		(duplicate_pad_numbers_are_jumpers no)
		(fp_line
			(start 0.508 0)
			(end -0.508 0)
			(stroke
				(width 0.2032)
				(type default)
			)
			(layer "F.SilkS")
		)
		(fp_rect
			(start -0.5842 1.3335)
			(end 0.5842 -1.3335)
			(stroke
				(width 0)
				(type default)
			)
			(fill no)
			(layer "F.CrtYd")
		)
		(fp_rect
			(start -0.5842 1.3335)
			(end 0.5842 -1.3335)
			(stroke
				(width 0)
				(type default)
			)
			(fill no)
			(layer "F.Fab")
		)
		(pad "1" smd custom
			(at 0 -0.762 180)
			(size 0.2159 0.2159)
			(layers "F.Cu" "F.Mask" "F.Paste")
			(net "P5V_HDD5")
			(options
				(clearance outline)
				(anchor circle)
			)
			(primitives
				(gr_poly
					(pts
						(arc
							(start -0.3302 -0.4318)
							(mid -0.402042 -0.402042)
							(end -0.4318 -0.3302)
						)
						(arc
							(start -0.4318 0.3302)
							(mid -0.402042 0.402042)
							(end -0.3302 0.4318)
						)
						(arc
							(start 0.3302 0.4318)
							(mid 0.402042 0.402042)
							(end 0.4318 0.3302)
						)
						(arc
							(start 0.4318 -0.3302)
							(mid 0.402042 -0.402042)
							(end 0.3302 -0.4318)
						)
					)
					(width 0)
					(fill yes)
				)
			)
		)
		(pad "2" smd custom
			(at 0 0.762 180)
			(size 0.2159 0.2159)
			(layers "F.Cu" "F.Mask" "F.Paste")
			(net "GND")
			(options
				(clearance outline)
				(anchor circle)
			)
			(primitives
				(gr_poly
					(pts
						(arc
							(start -0.3302 -0.4318)
							(mid -0.402042 -0.402042)
							(end -0.4318 -0.3302)
						)
						(arc
							(start -0.4318 0.3302)
							(mid -0.402042 0.402042)
							(end -0.3302 0.4318)
						)
						(arc
							(start 0.3302 0.4318)
							(mid 0.402042 0.402042)
							(end 0.4318 0.3302)
						)
						(arc
							(start 0.4318 -0.3302)
							(mid 0.402042 -0.402042)
							(end 0.3302 -0.4318)
						)
					)
					(width 0)
					(fill yes)
				)
			)
		)
	)
)
